# T6G (Grand Teton) — schematic netlist excerpt (pin names and nets, part order shuffled) for the footprints in the layout excerpt that follows; sources: Cadence DE-HDL packaged netlist, KiCad conversion of 04192023_DAF0TMB3IC0_F0TG_MB_C_brd_V02_OCP.brd

C1084  Q_CAP  100PF 50V 5% EMPTY  pkg 0402  page 258 : A = P1V8_AUX_ADC_MAM ; B = GND

X12  TP_TDR_4P_FTS  TP_TDR_4P_DIP EMPTY  pkg TH  page 260
  S1  = TDR_DIFF_80_BOT_DN
  P1  = T1_GND
  P2  = T1_GND
  S2  = TDR_DIFF_80_BOT_DP

(kicad_pcb
	(version 20260206)
	(generator "pcbnew")
	(generator_version "10.0")
	(general
		(thickness 1.6)
		(legacy_teardrops no)
	)
	(paper "A4")
	(title_block
		(title "04192023_DAF0TMB3IC0_F0TG_MB_C_brd_V02_OCP.brd")
		(comment 1 "Grand Teton / footprints 7080-7081 of 8354")
	)
	(layers
		(0 "F.Cu" signal "TOP")
		(4 "In1.Cu" signal "GND")
		(6 "In2.Cu" signal "IN1")
		(8 "In3.Cu" signal "GND1")
		(10 "In4.Cu" signal "IN2")
		(12 "In5.Cu" signal "GND2")
		(14 "In6.Cu" signal "IN3")
		(16 "In7.Cu" signal "GND3")
		(18 "In8.Cu" signal "VCC")
		(20 "In9.Cu" signal "VCC1")
		(22 "In10.Cu" signal "GND4")
		(24 "In11.Cu" signal "IN4")
		(26 "In12.Cu" signal "GND5")
		(28 "In13.Cu" signal "IN5")
		(30 "In14.Cu" signal "GND6")
		(32 "In15.Cu" signal "IN6")
		(34 "In16.Cu" signal "GND7")
		(2 "B.Cu" signal "BOTTOM")
		(9 "F.Adhes" user "F.Adhesive")
		(11 "B.Adhes" user "B.Adhesive")
		(13 "F.Paste" user "Package Geometry/Pastemask Top")
		(15 "B.Paste" user "Package Geometry/Pastemask Bottom")
		(5 "F.SilkS" user "Ref Des/Silkscreen Top")
		(7 "B.SilkS" user "Ref Des/Silkscreen Bottom")
		(1 "F.Mask" user "Board Geometry/Soldermask Top")
		(3 "B.Mask" user "Board Geometry/Soldermask Bottom")
		(17 "Dwgs.User" user "User.Drawings")
		(19 "Cmts.User" user "User.Comments")
		(21 "Eco1.User" user "User.Eco1")
		(23 "Eco2.User" user "User.Eco2")
		(25 "Edge.Cuts" user "Board Geometry/Outline")
		(27 "Margin" user)
		(31 "F.CrtYd" user "Package Geometry/Place Bound Top")
		(29 "B.CrtYd" user "Package Geometry/Place Bound Bottom")
		(35 "F.Fab" user "Ref Des/Assembly Top")
		(33 "B.Fab" user "Ref Des/Assembly Bottom")
	)
	(footprint ""
		(layer "B.Cu")
		(at 255.73736 -324.045072 180)
		(property "Reference" "C1084"
			(at 0 0 0)
			(layer "B.SilkS")
			(hide yes)
			(effects
				(font
					(size 1.27 1.27)
				)
				(justify mirror)
			)
		)
		(property "Value" ""
			(at 0 0 0)
			(layer "B.Fab")
			(effects
				(font
					(size 1.27 1.27)
				)
				(justify mirror)
			)
		)
		(duplicate_pad_numbers_are_jumpers no)
		(fp_line
			(start 0.7874 0.4064)
			(end 0.7874 -0.4064)
			(stroke
				(width 0.1524)
				(type default)
			)
			(layer "B.SilkS")
		)
		(fp_line
			(start 0.7874 -0.4064)
			(end -0.7874 -0.4064)
			(stroke
				(width 0.1524)
				(type default)
			)
			(layer "B.SilkS")
		)
		(fp_line
			(start -0.7874 0.4064)
			(end 0.7874 0.4064)
			(stroke
				(width 0.1524)
				(type default)
			)
			(layer "B.SilkS")
		)
		(fp_line
			(start -0.7874 -0.4064)
			(end -0.7874 0.4064)
			(stroke
				(width 0.1524)
				(type default)
			)
			(layer "B.SilkS")
		)
		(fp_line
			(start 0.67945 0.3048)
			(end 0.67945 -0.305054)
			(stroke
				(width 0.1)
				(type default)
			)
			(layer "B.Fab")
		)
		(fp_line
			(start 0.67945 -0.305054)
			(end 0.12065 -0.305054)
			(stroke
				(width 0.1)
				(type default)
			)
			(layer "B.Fab")
		)
		(fp_line
			(start 0.12065 0.3048)
			(end 0.67945 0.3048)
			(stroke
				(width 0.1)
				(type default)
			)
			(layer "B.Fab")
		)
		(fp_line
			(start 0.12065 0.2794)
			(end 0.12065 0.3048)
			(stroke
				(width 0.1)
				(type default)
			)
			(layer "B.Fab")
		)
		(fp_line
			(start 0.12065 -0.2794)
			(end -0.12065 -0.2794)
			(stroke
				(width 0.1)
				(type default)
			)
			(layer "B.Fab")
		)
		(fp_line
			(start 0.12065 -0.305054)
			(end 0.12065 -0.2794)
			(stroke
				(width 0.1)
				(type default)
			)
			(layer "B.Fab")
		)
		(fp_line
			(start -0.120396 0.3048)
			(end -0.120396 0.2794)
			(stroke
				(width 0.1)
				(type default)
			)
			(layer "B.Fab")
		)
		(fp_line
			(start -0.120396 0.2794)
			(end 0.12065 0.2794)
			(stroke
				(width 0.1)
				(type default)
			)
			(layer "B.Fab")
		)
		(fp_line
			(start -0.12065 -0.2794)
			(end -0.12065 -0.3048)
			(stroke
				(width 0.1)
				(type default)
			)
			(layer "B.Fab")
		)
		(fp_line
			(start -0.12065 -0.3048)
			(end -0.67945 -0.3048)
			(stroke
				(width 0.1)
				(type default)
			)
			(layer "B.Fab")
		)
		(fp_line
			(start -0.67945 0.3048)
			(end -0.120396 0.3048)
			(stroke
				(width 0.1)
				(type default)
			)
			(layer "B.Fab")
		)
		(fp_line
			(start -0.67945 -0.3048)
			(end -0.67945 0.3048)
			(stroke
				(width 0.1)
				(type default)
			)
			(layer "B.Fab")
		)
		(pad "1" smd circle
			(at 0.40005 0)
			(size 0 0)
			(layers "B.Cu" "B.Mask" "B.Paste")
			(net "P1V8_AUX_ADC_MAM")
		)
		(pad "2" smd circle
			(at -0.40005 0)
			(size 0 0)
			(layers "B.Cu" "B.Mask" "B.Paste")
			(net "GND")
		)
	)
	(footprint ""
		(layer "B.Cu")
		(at 490.57433 -298.306998 -90)
		(property "Reference" "X12"
			(at 2.985008 3.602736 270)
			(unlocked yes)
			(layer "B.SilkS")
			(effects
				(font
					(size 0.7874 0.5842)
					(thickness 0.1524)
				)
				(justify left mirror)
			)
		)
		(property "Value" ""
			(at 0 0 90)
			(layer "B.Fab")
			(effects
				(font
					(size 1.27 1.27)
				)
				(justify mirror)
			)
		)
		(property "User Part Number" "N_A"
			(at -1.30175 1.27 180)
			(unlocked yes)
			(layer "Cmts.User")
			(hide yes)
			(effects
				(font
					(size 0.635 0.4064)
					(thickness 0.1524)
				)
				(justify mirror)
			)
		)
		(property "Device Type" "TP_TDR_4P_FTS_TH-TP_TDR_4P_DIP,EMPTY,TP15"
			(at -1.30175 1.27 180)
			(unlocked yes)
			(layer "B.Fab")
			(hide yes)
			(effects
				(font
					(size 0.635 0.4064)
					(thickness 0.1524)
				)
				(justify mirror)
			)
		)
		(duplicate_pad_numbers_are_jumpers no)
		(fp_line
			(start -2.54 3.81)
			(end -2.54 3.6703)
			(stroke
				(width 0.1524)
				(type default)
			)
			(layer "B.SilkS")
		)
		(fp_line
			(start 0 3.81)
			(end -2.54 3.81)
			(stroke
				(width 0.1524)
				(type default)
			)
			(layer "B.SilkS")
		)
		(fp_line
			(start 0 3.175)
			(end 0 3.81)
			(stroke
				(width 0.1524)
				(type default)
			)
			(layer "B.SilkS")
		)
		(fp_line
			(start -2.54 1.4097)
			(end -2.54 1.1303)
			(stroke
				(width 0.1524)
				(type default)
			)
			(layer "B.SilkS")
		)
		(fp_line
			(start 0 0.635)
			(end 0 1.905)
			(stroke
				(width 0.1524)
				(type default)
			)
			(layer "B.SilkS")
		)
		(fp_line
			(start -2.54 -1.1303)
			(end -2.54 -1.27)
			(stroke
				(width 0.1524)
				(type default)
			)
			(layer "B.SilkS")
		)
		(fp_line
			(start -2.54 -1.27)
			(end 0 -1.27)
			(stroke
				(width 0.1524)
				(type default)
			)
			(layer "B.SilkS")
		)
		(fp_line
			(start 0 -1.27)
			(end 0 -0.635)
			(stroke
				(width 0.1524)
				(type default)
			)
			(layer "B.SilkS")
		)
		(fp_poly
			(pts
				(xy 2.285746 -0.762) (xy 2.285746 0.762) (xy 0.761746 0)
			)
			(stroke
				(width 0)
				(type default)
			)
			(fill yes)
			(layer "B.SilkS")
		)
		(fp_line
			(start -2.54 3.81)
			(end -2.54 -1.27)
			(stroke
				(width 0.1)
				(type default)
			)
			(layer "B.Fab")
		)
		(fp_line
			(start 0 3.81)
			(end -2.54 3.81)
			(stroke
				(width 0.1)
				(type default)
			)
			(layer "B.Fab")
		)
		(fp_line
			(start -2.54 -1.27)
			(end 0 -1.27)
			(stroke
				(width 0.1)
				(type default)
			)
			(layer "B.Fab")
		)
		(fp_line
			(start 0 -1.27)
			(end 0 3.81)
			(stroke
				(width 0.1)
				(type default)
			)
			(layer "B.Fab")
		)
		(fp_poly
			(pts
				(xy 0.761746 0) (xy 2.285746 -0.762) (xy 2.285746 0.762)
			)
			(stroke
				(width 0)
				(type default)
			)
			(fill yes)
			(layer "B.Fab")
		)
		(pad "1" thru_hole circle
			(at 0 0 90)
			(size 1.0033 1.0033)
			(drill 0.249936)
			(layers "*.Cu" "*.Mask")
			(remove_unused_layers no)
			(net "TDR_DIFF_80_BOT_DN")
			(clearance 0.10795)
			(padstack
				(mode front_inner_back)
				(layer "Inner"
					(shape circle)
					(size 0.8001 0.8001)
					(clearance 0.1524)
				)
				(layer "B.Cu"
					(shape circle)
					(size 1.0033 1.0033)
					(thermal_gap 0.10795)
					(clearance 0.10795)
				)
			)
		)
		(pad "2" thru_hole circle
			(at -2.54 0 90)
			(size 1.9939 1.9939)
			(drill 0.249936)
			(layers "*.Cu" "*.Mask")
			(remove_unused_layers no)
			(net "T1_GND")
			(clearance 0.10795)
			(padstack
				(mode front_inner_back)
				(layer "Inner"
					(shape circle)
					(size 0.8001 0.8001)
					(clearance 0.1524)
				)
				(layer "B.Cu"
					(shape circle)
					(size 1.9939 1.9939)
					(thermal_gap 0.10795)
					(clearance 0.10795)
				)
			)
		)
		(pad "3" thru_hole circle
			(at -2.54 2.54 90)
			(size 1.9939 1.9939)
			(drill 0.249936)
			(layers "*.Cu" "*.Mask")
			(remove_unused_layers no)
			(net "T1_GND")
			(clearance 0.10795)
			(padstack
				(mode front_inner_back)
				(layer "Inner"
					(shape circle)
					(size 0.8001 0.8001)
					(clearance 0.1524)
				)
				(layer "B.Cu"
					(shape circle)
					(size 1.9939 1.9939)
					(thermal_gap 0.10795)
					(clearance 0.10795)
				)
			)
		)
		(pad "4" thru_hole circle
			(at 0 2.54 90)
			(size 1.0033 1.0033)
			(drill 0.249936)
			(layers "*.Cu" "*.Mask")
			(remove_unused_layers no)
			(net "TDR_DIFF_80_BOT_DP")
			(clearance 0.10795)
			(padstack
				(mode front_inner_back)
				(layer "Inner"
					(shape circle)
					(size 0.8001 0.8001)
					(clearance 0.1524)
				)
				(layer "B.Cu"
					(shape circle)
					(size 1.0033 1.0033)
					(thermal_gap 0.10795)
					(clearance 0.10795)
				)
			)
		)
	)
)
